# BASEBOARD_FAB2 (Tioga Pass) — schematic netlist excerpt (pin names and nets, part order shuffled) for the footprints in the layout excerpt that follows; sources: Cadence DE-HDL packaged netlist, KiCad conversion of Wiwynn_Tioga_Pass_MB.brd

C5G107  CAP_A  22.0UF 4V 20% X6S  pkg 0603V  page 243 : A = PVDDQ_KLM ; B = GND
R2U50  RES  0.0 5% CHIP  pkg 0402  page 119 : A = FM_SLT_CFG2_R ; B = FM_PWRBRK_SLOT_N
C5P6  CAP  100UF 4V 20% X5R  pkg 0805  page 220 : A = PVDDQ_DEF ; B = GND

(kicad_pcb
	(version 20260206)
	(generator "pcbnew")
	(generator_version "10.0")
	(general
		(thickness 1.6)
		(legacy_teardrops no)
	)
	(paper "A4")
	(title_block
		(title "Wiwynn_Tioga_Pass_MB.brd")
		(comment 1 "Tioga Pass / footprints 4130-4132 of 4770")
	)
	(layers
		(0 "F.Cu" signal "TOP")
		(4 "In1.Cu" signal "L2GND")
		(6 "In2.Cu" signal "L3")
		(8 "In3.Cu" signal "L4GND")
		(10 "In4.Cu" signal "L5")
		(12 "In5.Cu" signal "L6GND")
		(14 "In6.Cu" signal "L7VCC")
		(16 "In7.Cu" signal "L8VCC")
		(18 "In8.Cu" signal "L9GND")
		(20 "In9.Cu" signal "L10")
		(22 "In10.Cu" signal "L11GND")
		(24 "In11.Cu" signal "L12")
		(26 "In12.Cu" signal "L13GND")
		(2 "B.Cu" signal "BOTTOM")
		(9 "F.Adhes" user "F.Adhesive")
		(11 "B.Adhes" user "B.Adhesive")
		(13 "F.Paste" user "Package Geometry/Pastemask Top")
		(15 "B.Paste" user "Package Geometry/Pastemask Bottom")
		(5 "F.SilkS" user "Ref Des/Silkscreen Top")
		(7 "B.SilkS" user "Ref Des/Silkscreen Bottom")
		(1 "F.Mask" user "Board Geometry/Soldermask Top")
		(3 "B.Mask" user "Board Geometry/Soldermask Bottom")
		(17 "Dwgs.User" user "User.Drawings")
		(19 "Cmts.User" user "User.Comments")
		(21 "Eco1.User" user "User.Eco1")
		(23 "Eco2.User" user "User.Eco2")
		(25 "Edge.Cuts" user "Board Geometry/Outline")
		(27 "Margin" user)
		(31 "F.CrtYd" user "Package Geometry/Place Bound Top")
		(29 "B.CrtYd" user "Package Geometry/Place Bound Bottom")
		(35 "F.Fab" user "Ref Des/Assembly Top")
		(33 "B.Fab" user "Ref Des/Assembly Bottom")
	)
	(footprint ""
		(layer "B.Cu")
		(at 104.5591 -140.208 90)
		(property "Reference" "C5G107"
			(at -1.14681 0.76708 180)
			(unlocked yes)
			(layer "B.SilkS")
			(effects
				(font
					(size 0.7874 0.5842)
					(thickness 0.1524)
				)
				(justify mirror)
			)
		)
		(property "Value" ""
			(at 0 0 90)
			(layer "B.Fab")
			(effects
				(font
					(size 1.27 1.27)
				)
				(justify mirror)
			)
		)
		(duplicate_pad_numbers_are_jumpers no)
		(fp_rect
			(start -0.4953 -0.2032)
			(end 0.4953 1.6002)
			(stroke
				(width 0)
				(type default)
			)
			(fill no)
			(layer "B.CrtYd")
		)
		(fp_line
			(start 0.4953 -0.2032)
			(end -0.4953 -0.2032)
			(stroke
				(width 0.1)
				(type default)
			)
			(layer "B.Fab")
		)
		(fp_line
			(start -0.4953 -0.2032)
			(end -0.4953 1.6002)
			(stroke
				(width 0.1)
				(type default)
			)
			(layer "B.Fab")
		)
		(fp_line
			(start 0.4953 1.6002)
			(end 0.4953 -0.2032)
			(stroke
				(width 0.1)
				(type default)
			)
			(layer "B.Fab")
		)
		(fp_line
			(start -0.4953 1.6002)
			(end 0.4953 1.6002)
			(stroke
				(width 0.1)
				(type default)
			)
			(layer "B.Fab")
		)
		(pad "1" smd rect
			(at 0 0 270)
			(size 0.762 0.889)
			(layers "B.Cu" "B.Mask" "B.Paste")
			(net "PVDDQ_KLM")
		)
		(pad "2" smd rect
			(at 0 1.397 270)
			(size 0.762 0.889)
			(layers "B.Cu" "B.Mask" "B.Paste")
			(net "GND")
		)
		(zone
			(layer "B.Cu")
			(hatch none 0.5)
			(connect_pads
				(clearance 0)
			)
			(min_thickness 0.25)
			(keepout
				(tracks not_allowed)
				(vias allowed)
				(pads allowed)
				(copperpour not_allowed)
				(footprints allowed)
			)
			(placement
				(enabled no)
				(sheetname "")
			)
			(fill
				(thermal_gap 0.5)
				(thermal_bridge_width 0.5)
				(island_removal_mode 0)
			)
			(polygon
				(pts
					(xy 105.0036 -139.827) (xy 105.5116 -139.827) (xy 105.5116 -140.589) (xy 105.0036 -140.589)
				)
			)
		)
	)
	(footprint ""
		(layer "B.Cu")
		(at 466.1535 -4.445 90)
		(property "Reference" "R2U50"
			(at 0 0 90)
			(layer "B.SilkS")
			(hide yes)
			(effects
				(font
					(size 1.27 1.27)
				)
				(justify mirror)
			)
		)
		(property "Value" ""
			(at 0 0 90)
			(layer "B.Fab")
			(effects
				(font
					(size 1.27 1.27)
				)
				(justify mirror)
			)
		)
		(duplicate_pad_numbers_are_jumpers no)
		(fp_poly
			(pts
				(xy 0.2794 -0.1016) (xy -0.2794 -0.1016) (xy -0.2794 0.9906) (xy 0.2794 0.9906)
			)
			(stroke
				(width 0)
				(type default)
			)
			(fill no)
			(layer "B.CrtYd")
		)
		(fp_line
			(start 0.2794 -0.1016)
			(end 0.2794 0.9906)
			(stroke
				(width 0.1)
				(type default)
			)
			(layer "B.Fab")
		)
		(fp_line
			(start -0.2794 -0.1016)
			(end 0.2794 -0.1016)
			(stroke
				(width 0.1)
				(type default)
			)
			(layer "B.Fab")
		)
		(fp_line
			(start 0.2794 0.9906)
			(end -0.2794 0.9906)
			(stroke
				(width 0.1)
				(type default)
			)
			(layer "B.Fab")
		)
		(fp_line
			(start -0.2794 0.9906)
			(end -0.2794 -0.1016)
			(stroke
				(width 0.1)
				(type default)
			)
			(layer "B.Fab")
		)
		(pad "1" smd rect
			(at 0 0 270)
			(size 0.508 0.508)
			(layers "B.Cu" "B.Mask" "B.Paste")
			(net "FM_SLT_CFG2_R")
		)
		(pad "2" smd rect
			(at 0 0.889 270)
			(size 0.508 0.508)
			(layers "B.Cu" "B.Mask" "B.Paste")
			(net "FM_PWRBRK_SLOT_N")
		)
		(zone
			(layer "B.Cu")
			(hatch none 0.5)
			(connect_pads
				(clearance 0)
			)
			(min_thickness 0.25)
			(keepout
				(tracks allowed)
				(vias not_allowed)
				(pads allowed)
				(copperpour not_allowed)
				(footprints allowed)
			)
			(placement
				(enabled no)
				(sheetname "")
			)
			(fill
				(thermal_gap 0.5)
				(thermal_bridge_width 0.5)
				(island_removal_mode 0)
			)
			(polygon
				(pts
					(xy 466.4075 -4.699) (xy 466.4075 -4.191) (xy 466.7885 -4.191) (xy 466.7885 -4.699)
				)
			)
		)
		(zone
			(layer "B.Cu")
			(hatch none 0.5)
			(connect_pads
				(clearance 0)
			)
			(min_thickness 0.25)
			(keepout
				(tracks not_allowed)
				(vias allowed)
				(pads allowed)
				(copperpour not_allowed)
				(footprints allowed)
			)
			(placement
				(enabled no)
				(sheetname "")
			)
			(fill
				(thermal_gap 0.5)
				(thermal_bridge_width 0.5)
				(island_removal_mode 0)
			)
			(polygon
				(pts
					(xy 466.7885 -4.699) (xy 466.7885 -4.191) (xy 466.4075 -4.191) (xy 466.4075 -4.699)
				)
			)
		)
	)
	(footprint ""
		(layer "B.Cu")
		(at 269.394686 -85.06714)
		(property "Reference" "C5P6"
			(at 0 0 0)
			(layer "B.SilkS")
			(hide yes)
			(effects
				(font
					(size 1.27 1.27)
				)
				(justify mirror)
			)
		)
		(property "Value" ""
			(at 0 0 0)
			(layer "B.Fab")
			(effects
				(font
					(size 1.27 1.27)
				)
				(justify mirror)
			)
		)
		(duplicate_pad_numbers_are_jumpers no)
		(fp_poly
			(pts
				(xy 0.7239 -0.2159) (xy -0.7239 -0.2159) (xy -0.7239 1.9939) (xy 0.7239 1.9939)
			)
			(stroke
				(width 0)
				(type default)
			)
			(fill no)
			(layer "B.CrtYd")
		)
		(fp_line
			(start -0.7239 -0.2159)
			(end 0.7239 -0.2159)
			(stroke
				(width 0.1)
				(type default)
			)
			(layer "B.Fab")
		)
		(fp_line
			(start -0.7239 1.9939)
			(end -0.7239 -0.2159)
			(stroke
				(width 0.1)
				(type default)
			)
			(layer "B.Fab")
		)
		(fp_line
			(start 0.7239 -0.2159)
			(end 0.7239 1.9939)
			(stroke
				(width 0.1)
				(type default)
			)
			(layer "B.Fab")
		)
		(fp_line
			(start 0.7239 1.9939)
			(end -0.7239 1.9939)
			(stroke
				(width 0.1)
				(type default)
			)
			(layer "B.Fab")
		)
		(pad "1" smd rect
			(at 0 0 180)
			(size 1.27 1.016)
			(layers "B.Cu" "B.Mask" "B.Paste")
			(net "PVDDQ_DEF")
		)
		(pad "2" smd rect
			(at 0 1.778 180)
			(size 1.27 1.016)
			(layers "B.Cu" "B.Mask" "B.Paste")
			(net "GND")
		)
		(zone
			(layer "B.Cu")
			(hatch none 0.5)
			(connect_pads
				(clearance 0)
			)
			(min_thickness 0.25)
			(keepout
				(tracks not_allowed)
				(vias allowed)
				(pads allowed)
				(copperpour not_allowed)
				(footprints allowed)
			)
			(placement
				(enabled no)
				(sheetname "")
			)
			(fill
				(thermal_gap 0.5)
				(thermal_bridge_width 0.5)
				(island_removal_mode 0)
			)
			(polygon
				(pts
					(xy 270.029686 -84.55914) (xy 268.759686 -84.55914) (xy 268.759686 -83.79714) (xy 270.029686 -83.79714)
				)
			)
		)
	)
)
